# T6G (Grand Teton) — schematic netlist excerpt (pin names and nets, part order shuffled) for the footprints in the layout excerpt that follows; sources: Cadence DE-HDL packaged netlist, KiCad conversion of 04192023_DAF0TMB3IC0_F0TG_MB_C_brd_V02_OCP.brd

C202  Q_CAP  1UF 4V 20% X6S  pkg 0201  page 334 : A = P1V8_CPU1_RT1_1A ; B = GND
R909  Q_RES  4.7K 5% EMPTY  pkg 0201LF  page 353 : A = P1V8_CPU1_RT_1D ; B = RT_CPU1_P3_SCAN_MODE
C171  Q_CAP  10UF 25V 10% X6S  pkg C0805  page 97 : A = P12V_MEM_CPU0 ; B = GND
PC277  Q_CAPP  220UF 4V 20% SPCAP  pkg SMLF  page 211 : A = PVDDCR_CPU0_P1 ; B = GND

(kicad_pcb
	(version 20260206)
	(generator "pcbnew")
	(generator_version "10.0")
	(general
		(thickness 1.6)
		(legacy_teardrops no)
	)
	(paper "A4")
	(title_block
		(title "04192023_DAF0TMB3IC0_F0TG_MB_C_brd_V02_OCP.brd")
		(comment 1 "Grand Teton / footprints 5725-5728 of 8354")
	)
	(layers
		(0 "F.Cu" signal "TOP")
		(4 "In1.Cu" signal "GND")
		(6 "In2.Cu" signal "IN1")
		(8 "In3.Cu" signal "GND1")
		(10 "In4.Cu" signal "IN2")
		(12 "In5.Cu" signal "GND2")
		(14 "In6.Cu" signal "IN3")
		(16 "In7.Cu" signal "GND3")
		(18 "In8.Cu" signal "VCC")
		(20 "In9.Cu" signal "VCC1")
		(22 "In10.Cu" signal "GND4")
		(24 "In11.Cu" signal "IN4")
		(26 "In12.Cu" signal "GND5")
		(28 "In13.Cu" signal "IN5")
		(30 "In14.Cu" signal "GND6")
		(32 "In15.Cu" signal "IN6")
		(34 "In16.Cu" signal "GND7")
		(2 "B.Cu" signal "BOTTOM")
		(9 "F.Adhes" user "F.Adhesive")
		(11 "B.Adhes" user "B.Adhesive")
		(13 "F.Paste" user "Package Geometry/Pastemask Top")
		(15 "B.Paste" user "Package Geometry/Pastemask Bottom")
		(5 "F.SilkS" user "Ref Des/Silkscreen Top")
		(7 "B.SilkS" user "Ref Des/Silkscreen Bottom")
		(1 "F.Mask" user "Board Geometry/Soldermask Top")
		(3 "B.Mask" user "Board Geometry/Soldermask Bottom")
		(17 "Dwgs.User" user "User.Drawings")
		(19 "Cmts.User" user "User.Comments")
		(21 "Eco1.User" user "User.Eco1")
		(23 "Eco2.User" user "User.Eco2")
		(25 "Edge.Cuts" user "Board Geometry/Outline")
		(27 "Margin" user)
		(31 "F.CrtYd" user "Package Geometry/Place Bound Top")
		(29 "B.CrtYd" user "Package Geometry/Place Bound Bottom")
		(35 "F.Fab" user "Ref Des/Assembly Top")
		(33 "B.Fab" user "Ref Des/Assembly Bottom")
	)
	(footprint ""
		(layer "B.Cu")
		(at 109.095794 -383.7432 180)
		(property "Reference" "R909"
			(at 0 0 0)
			(layer "B.SilkS")
			(hide yes)
			(effects
				(font
					(size 1.27 1.27)
				)
				(justify mirror)
			)
		)
		(property "Value" ""
			(at 0 0 0)
			(layer "B.Fab")
			(effects
				(font
					(size 1.27 1.27)
				)
				(justify mirror)
			)
		)
		(duplicate_pad_numbers_are_jumpers no)
		(fp_line
			(start 0.32512 0.175006)
			(end 0.32512 -0.175006)
			(stroke
				(width 0.1)
				(type default)
			)
			(layer "B.Fab")
		)
		(fp_line
			(start 0.32512 -0.175006)
			(end -0.32512 -0.175006)
			(stroke
				(width 0.1)
				(type default)
			)
			(layer "B.Fab")
		)
		(fp_line
			(start -0.32512 0.175006)
			(end 0.32512 0.175006)
			(stroke
				(width 0.1)
				(type default)
			)
			(layer "B.Fab")
		)
		(fp_line
			(start -0.32512 -0.175006)
			(end -0.32512 0.175006)
			(stroke
				(width 0.1)
				(type default)
			)
			(layer "B.Fab")
		)
		(pad "1" smd rect
			(at 0.2667 0)
			(size 0.3048 0.381)
			(layers "B.Cu" "B.Mask" "B.Paste")
			(net "P1V8_CPU1_RT_1D")
		)
		(pad "2" smd rect
			(at -0.2667 0 180)
			(size 0.3048 0.381)
			(layers "B.Cu" "B.Mask" "B.Paste")
			(net "RT_CPU1_P3_SCAN_MODE")
		)
	)
	(footprint ""
		(layer "B.Cu")
		(at 88.446356 -388.011162 -90)
		(property "Reference" "C202"
			(at 0 0 90)
			(layer "B.SilkS")
			(hide yes)
			(effects
				(font
					(size 1.27 1.27)
				)
				(justify mirror)
			)
		)
		(property "Value" ""
			(at 0 0 90)
			(layer "B.Fab")
			(effects
				(font
					(size 1.27 1.27)
				)
				(justify mirror)
			)
		)
		(duplicate_pad_numbers_are_jumpers no)
		(fp_line
			(start -0.299974 0.150114)
			(end 0.299974 0.150114)
			(stroke
				(width 0.1)
				(type default)
			)
			(layer "B.Fab")
		)
		(fp_line
			(start 0.299974 0.150114)
			(end 0.299974 -0.150114)
			(stroke
				(width 0.1)
				(type default)
			)
			(layer "B.Fab")
		)
		(fp_line
			(start -0.299974 -0.150114)
			(end -0.299974 0.150114)
			(stroke
				(width 0.1)
				(type default)
			)
			(layer "B.Fab")
		)
		(fp_line
			(start 0.299974 -0.150114)
			(end -0.299974 -0.150114)
			(stroke
				(width 0.1)
				(type default)
			)
			(layer "B.Fab")
		)
		(pad "1" smd rect
			(at 0.2667 0 90)
			(size 0.3048 0.381)
			(layers "B.Cu" "B.Mask" "B.Paste")
			(net "P1V8_CPU1_RT1_1A")
		)
		(pad "2" smd rect
			(at -0.2667 0 90)
			(size 0.3048 0.381)
			(layers "B.Cu" "B.Mask" "B.Paste")
			(net "GND")
		)
	)
	(footprint ""
		(layer "B.Cu")
		(at 450.088 -192.660016 180)
		(property "Reference" "C171"
			(at 0 0 0)
			(layer "B.SilkS")
			(hide yes)
			(effects
				(font
					(size 1.27 1.27)
				)
				(justify mirror)
			)
		)
		(property "Value" ""
			(at 0 0 0)
			(layer "B.Fab")
			(effects
				(font
					(size 1.27 1.27)
				)
				(justify mirror)
			)
		)
		(duplicate_pad_numbers_are_jumpers no)
		(fp_line
			(start 1.524 0.762)
			(end 1.524 -0.762)
			(stroke
				(width 0.1524)
				(type default)
			)
			(layer "B.SilkS")
		)
		(fp_line
			(start 1.524 -0.762)
			(end -1.524 -0.762)
			(stroke
				(width 0.1524)
				(type default)
			)
			(layer "B.SilkS")
		)
		(fp_line
			(start -1.524 0.762)
			(end 1.524 0.762)
			(stroke
				(width 0.1524)
				(type default)
			)
			(layer "B.SilkS")
		)
		(fp_line
			(start -1.524 -0.762)
			(end -1.524 0.762)
			(stroke
				(width 0.1524)
				(type default)
			)
			(layer "B.SilkS")
		)
		(fp_line
			(start 1.1049 0.724916)
			(end -1.1049 0.724916)
			(stroke
				(width 0.1)
				(type default)
			)
			(layer "B.Fab")
		)
		(fp_line
			(start 1.1049 -0.724916)
			(end 1.1049 0.724916)
			(stroke
				(width 0.1)
				(type default)
			)
			(layer "B.Fab")
		)
		(fp_line
			(start -1.1049 0.724916)
			(end -1.1049 -0.724916)
			(stroke
				(width 0.1)
				(type default)
			)
			(layer "B.Fab")
		)
		(fp_line
			(start -1.1049 -0.724916)
			(end 1.1049 -0.724916)
			(stroke
				(width 0.1)
				(type default)
			)
			(layer "B.Fab")
		)
		(pad "1" smd rect
			(at 0.889 0 180)
			(size 1.016 1.27)
			(layers "B.Cu" "B.Mask" "B.Paste")
			(net "P12V_MEM_CPU0")
		)
		(pad "2" smd rect
			(at -0.889 0 180)
			(size 1.016 1.27)
			(layers "B.Cu" "B.Mask" "B.Paste")
			(net "GND")
		)
	)
	(footprint ""
		(layer "B.Cu")
		(at 83.045554 -189.461648 90)
		(property "Reference" "PC277"
			(at 5.774436 -1.099566 270)
			(unlocked yes)
			(layer "B.SilkS")
			(effects
				(font
					(size 0.7874 0.5842)
					(thickness 0.1524)
				)
				(justify left mirror)
			)
		)
		(property "Value" ""
			(at 0 0 90)
			(layer "B.Fab")
			(effects
				(font
					(size 1.27 1.27)
				)
				(justify mirror)
			)
		)
		(duplicate_pad_numbers_are_jumpers no)
		(fp_line
			(start 4.533392 -2.249932)
			(end -4.533392 -2.249932)
			(stroke
				(width 0.1524)
				(type default)
			)
			(layer "B.SilkS")
		)
		(fp_line
			(start -4.533392 -2.249932)
			(end -4.533392 2.249932)
			(stroke
				(width 0.1524)
				(type default)
			)
			(layer "B.SilkS")
		)
		(fp_line
			(start 4.533392 2.249932)
			(end 4.533392 -2.249932)
			(stroke
				(width 0.1524)
				(type default)
			)
			(layer "B.SilkS")
		)
		(fp_line
			(start -4.533392 2.249932)
			(end 4.533392 2.249932)
			(stroke
				(width 0.1524)
				(type default)
			)
			(layer "B.SilkS")
		)
		(fp_rect
			(start 4.533392 -2.326132)
			(end 5.39242 2.326132)
			(stroke
				(width 0)
				(type default)
			)
			(fill yes)
			(layer "B.SilkS")
		)
		(fp_line
			(start 3.750056 -2.249932)
			(end -3.750056 -2.249932)
			(stroke
				(width 0.1)
				(type default)
			)
			(layer "B.Fab")
		)
		(fp_line
			(start -3.750056 -2.249932)
			(end -3.750056 2.249932)
			(stroke
				(width 0.1)
				(type default)
			)
			(layer "B.Fab")
		)
		(fp_line
			(start 3.750056 2.249932)
			(end 3.750056 -2.249932)
			(stroke
				(width 0.1)
				(type default)
			)
			(layer "B.Fab")
		)
		(fp_line
			(start -3.750056 2.249932)
			(end 3.750056 2.249932)
			(stroke
				(width 0.1)
				(type default)
			)
			(layer "B.Fab")
		)
		(fp_text user "-"
			(at -4.8514 -0.14605 90)
			(unlocked yes)
			(layer "B.SilkS")
			(effects
				(font
					(size 1.905 1.4224)
					(thickness 0.1524)
				)
				(justify left mirror)
			)
		)
		(fp_text user "+"
			(at 6.322314 0.786384 0)
			(unlocked yes)
			(layer "B.SilkS")
			(effects
				(font
					(size 1.905 1.4224)
					(thickness 0.1524)
				)
				(justify left mirror)
			)
		)
		(fp_text user "-"
			(at -4.8514 -0.14605 90)
			(unlocked yes)
			(layer "B.Fab")
			(effects
				(font
					(size 1.905 1.4224)
					(thickness 0.1524)
				)
				(justify left mirror)
			)
		)
		(fp_text user "+"
			(at 6.322314 0.786384 0)
			(unlocked yes)
			(layer "B.Fab")
			(effects
				(font
					(size 1.905 1.4224)
					(thickness 0.1524)
				)
				(justify left mirror)
			)
		)
		(pad "1" smd rect
			(at 3.199892 0 270)
			(size 2.413 2.8194)
			(layers "B.Cu" "B.Mask" "B.Paste")
			(net "PVDDCR_CPU0_P1")
		)
		(pad "2" smd rect
			(at -3.199892 0 270)
			(size 2.413 2.8194)
			(layers "B.Cu" "B.Mask" "B.Paste")
			(net "GND")
		)
	)
)
